# T6G (Grand Teton) — schematic netlist excerpt (pin names and nets, part order shuffled) for the footprints in the layout excerpt that follows; sources: Cadence DE-HDL packaged netlist, KiCad conversion of 04192023_DAF0TMB3IC0_F0TG_MB_C_brd_V02_OCP.brd

R1082  Q_RES  200 1% CHIP  pkg 0201LF  page 299 : A = RT_CPU0_P2_VQPS ; B = GND
R3199  Q_RES  0 5% CHIP  pkg 0402LF  page 55 : A = CLK_100M_CPU1_CLK04_R_DN ; B = CLK_100M_CPU1_CLK04_DN
PC408_3  Q_CAP  0.1UF 25V 10% X7R  pkg 0402  page 219 : A = SW_P12V_AUX_PVDDCR_CPU1_P1_FLT ; B = GND

(kicad_pcb
	(version 20260206)
	(generator "pcbnew")
	(generator_version "10.0")
	(general
		(thickness 1.6)
		(legacy_teardrops no)
	)
	(paper "A4")
	(title_block
		(title "04192023_DAF0TMB3IC0_F0TG_MB_C_brd_V02_OCP.brd")
		(comment 1 "Grand Teton / footprints 888-890 of 8354")
	)
	(layers
		(0 "F.Cu" signal "TOP")
		(4 "In1.Cu" signal "GND")
		(6 "In2.Cu" signal "IN1")
		(8 "In3.Cu" signal "GND1")
		(10 "In4.Cu" signal "IN2")
		(12 "In5.Cu" signal "GND2")
		(14 "In6.Cu" signal "IN3")
		(16 "In7.Cu" signal "GND3")
		(18 "In8.Cu" signal "VCC")
		(20 "In9.Cu" signal "VCC1")
		(22 "In10.Cu" signal "GND4")
		(24 "In11.Cu" signal "IN4")
		(26 "In12.Cu" signal "GND5")
		(28 "In13.Cu" signal "IN5")
		(30 "In14.Cu" signal "GND6")
		(32 "In15.Cu" signal "IN6")
		(34 "In16.Cu" signal "GND7")
		(2 "B.Cu" signal "BOTTOM")
		(9 "F.Adhes" user "F.Adhesive")
		(11 "B.Adhes" user "B.Adhesive")
		(13 "F.Paste" user "Package Geometry/Pastemask Top")
		(15 "B.Paste" user "Package Geometry/Pastemask Bottom")
		(5 "F.SilkS" user "Ref Des/Silkscreen Top")
		(7 "B.SilkS" user "Ref Des/Silkscreen Bottom")
		(1 "F.Mask" user "Board Geometry/Soldermask Top")
		(3 "B.Mask" user "Board Geometry/Soldermask Bottom")
		(17 "Dwgs.User" user "User.Drawings")
		(19 "Cmts.User" user "User.Comments")
		(21 "Eco1.User" user "User.Eco1")
		(23 "Eco2.User" user "User.Eco2")
		(25 "Edge.Cuts" user "Board Geometry/Outline")
		(27 "Margin" user)
		(31 "F.CrtYd" user "Package Geometry/Place Bound Top")
		(29 "B.CrtYd" user "Package Geometry/Place Bound Bottom")
		(35 "F.Fab" user "Ref Des/Assembly Top")
		(33 "B.Fab" user "Ref Des/Assembly Bottom")
	)
	(footprint ""
		(layer "F.Cu")
		(at 148.11375 -191.35471 -90)
		(property "Reference" "R3199"
			(at 0 0 270)
			(layer "F.SilkS")
			(hide yes)
			(effects
				(font
					(size 1.27 1.27)
				)
			)
		)
		(property "Value" ""
			(at 0 0 270)
			(layer "F.Fab")
			(effects
				(font
					(size 1.27 1.27)
				)
			)
		)
		(duplicate_pad_numbers_are_jumpers no)
		(fp_line
			(start 0.42291 0.4064)
			(end -0.33909 0.4064)
			(stroke
				(width 0.1524)
				(type default)
			)
			(layer "F.SilkS")
		)
		(fp_line
			(start -0.7874 -0.04445)
			(end -0.7874 -0.4064)
			(stroke
				(width 0.1524)
				(type default)
			)
			(layer "F.SilkS")
		)
		(fp_line
			(start -0.7874 -0.4064)
			(end 0.7874 -0.4064)
			(stroke
				(width 0.1524)
				(type default)
			)
			(layer "F.SilkS")
		)
		(fp_line
			(start 0.7874 -0.4064)
			(end 0.7874 -0.01905)
			(stroke
				(width 0.1524)
				(type default)
			)
			(layer "F.SilkS")
		)
		(fp_line
			(start -0.67945 0.3048)
			(end -0.67945 -0.305054)
			(stroke
				(width 0.1)
				(type default)
			)
			(layer "F.Fab")
		)
		(fp_line
			(start -0.12065 0.3048)
			(end -0.67945 0.3048)
			(stroke
				(width 0.1)
				(type default)
			)
			(layer "F.Fab")
		)
		(fp_line
			(start 0.120396 0.3048)
			(end 0.120396 0.2794)
			(stroke
				(width 0.1)
				(type default)
			)
			(layer "F.Fab")
		)
		(fp_line
			(start 0.67945 0.3048)
			(end 0.120396 0.3048)
			(stroke
				(width 0.1)
				(type default)
			)
			(layer "F.Fab")
		)
		(fp_line
			(start -0.12065 0.2794)
			(end -0.12065 0.3048)
			(stroke
				(width 0.1)
				(type default)
			)
			(layer "F.Fab")
		)
		(fp_line
			(start 0.120396 0.2794)
			(end -0.12065 0.2794)
			(stroke
				(width 0.1)
				(type default)
			)
			(layer "F.Fab")
		)
		(fp_line
			(start -0.12065 -0.2794)
			(end 0.12065 -0.2794)
			(stroke
				(width 0.1)
				(type default)
			)
			(layer "F.Fab")
		)
		(fp_line
			(start 0.12065 -0.2794)
			(end 0.12065 -0.3048)
			(stroke
				(width 0.1)
				(type default)
			)
			(layer "F.Fab")
		)
		(fp_line
			(start 0.12065 -0.3048)
			(end 0.67945 -0.3048)
			(stroke
				(width 0.1)
				(type default)
			)
			(layer "F.Fab")
		)
		(fp_line
			(start 0.67945 -0.3048)
			(end 0.67945 0.3048)
			(stroke
				(width 0.1)
				(type default)
			)
			(layer "F.Fab")
		)
		(fp_line
			(start -0.67945 -0.305054)
			(end -0.12065 -0.305054)
			(stroke
				(width 0.1)
				(type default)
			)
			(layer "F.Fab")
		)
		(fp_line
			(start -0.12065 -0.305054)
			(end -0.12065 -0.2794)
			(stroke
				(width 0.1)
				(type default)
			)
			(layer "F.Fab")
		)
		(pad "1" smd circle
			(at -0.40005 0 270)
			(size 0 0)
			(layers "F.Cu" "F.Mask" "F.Paste")
			(net "CLK_100M_CPU1_CLK04_R_DN")
		)
		(pad "2" smd circle
			(at 0.40005 0 270)
			(size 0 0)
			(layers "F.Cu" "F.Mask" "F.Paste")
			(net "CLK_100M_CPU1_CLK04_DN")
		)
	)
	(footprint ""
		(layer "F.Cu")
		(at 422.180766 -402.7424 -90)
		(property "Reference" "R1082"
			(at 0 0 270)
			(layer "F.SilkS")
			(hide yes)
			(effects
				(font
					(size 1.27 1.27)
				)
			)
		)
		(property "Value" ""
			(at 0 0 270)
			(layer "F.Fab")
			(effects
				(font
					(size 1.27 1.27)
				)
			)
		)
		(duplicate_pad_numbers_are_jumpers no)
		(fp_line
			(start -0.32512 0.175006)
			(end -0.32512 -0.175006)
			(stroke
				(width 0.1)
				(type default)
			)
			(layer "F.Fab")
		)
		(fp_line
			(start 0.32512 0.175006)
			(end -0.32512 0.175006)
			(stroke
				(width 0.1)
				(type default)
			)
			(layer "F.Fab")
		)
		(fp_line
			(start -0.32512 -0.175006)
			(end 0.32512 -0.175006)
			(stroke
				(width 0.1)
				(type default)
			)
			(layer "F.Fab")
		)
		(fp_line
			(start 0.32512 -0.175006)
			(end 0.32512 0.175006)
			(stroke
				(width 0.1)
				(type default)
			)
			(layer "F.Fab")
		)
		(pad "1" smd rect
			(at -0.2667 0 270)
			(size 0.3048 0.381)
			(layers "F.Cu" "F.Mask" "F.Paste")
			(net "RT_CPU0_P2_VQPS")
		)
		(pad "2" smd rect
			(at 0.2667 0 90)
			(size 0.3048 0.381)
			(layers "F.Cu" "F.Mask" "F.Paste")
			(net "GND")
		)
	)
	(footprint ""
		(layer "F.Cu")
		(at 72.635618 -341.04707 180)
		(property "Reference" "PC408_3"
			(at 0 0 180)
			(layer "F.SilkS")
			(hide yes)
			(effects
				(font
					(size 1.27 1.27)
				)
			)
		)
		(property "Value" ""
			(at 0 0 180)
			(layer "F.Fab")
			(effects
				(font
					(size 1.27 1.27)
				)
			)
		)
		(duplicate_pad_numbers_are_jumpers no)
		(fp_line
			(start 0.7874 0.4064)
			(end -0.7874 0.4064)
			(stroke
				(width 0.1524)
				(type default)
			)
			(layer "F.SilkS")
		)
		(fp_line
			(start 0.7874 -0.4064)
			(end 0.7874 0.4064)
			(stroke
				(width 0.1524)
				(type default)
			)
			(layer "F.SilkS")
		)
		(fp_line
			(start -0.7874 0.4064)
			(end -0.7874 -0.4064)
			(stroke
				(width 0.1524)
				(type default)
			)
			(layer "F.SilkS")
		)
		(fp_line
			(start -0.7874 -0.4064)
			(end 0.7874 -0.4064)
			(stroke
				(width 0.1524)
				(type default)
			)
			(layer "F.SilkS")
		)
		(fp_line
			(start 0.67945 0.3048)
			(end 0.120396 0.3048)
			(stroke
				(width 0.1)
				(type default)
			)
			(layer "F.Fab")
		)
		(fp_line
			(start 0.67945 -0.3048)
			(end 0.67945 0.3048)
			(stroke
				(width 0.1)
				(type default)
			)
			(layer "F.Fab")
		)
		(fp_line
			(start 0.12065 -0.2794)
			(end 0.12065 -0.3048)
			(stroke
				(width 0.1)
				(type default)
			)
			(layer "F.Fab")
		)
		(fp_line
			(start 0.12065 -0.3048)
			(end 0.67945 -0.3048)
			(stroke
				(width 0.1)
				(type default)
			)
			(layer "F.Fab")
		)
		(fp_line
			(start 0.120396 0.3048)
			(end 0.120396 0.2794)
			(stroke
				(width 0.1)
				(type default)
			)
			(layer "F.Fab")
		)
		(fp_line
			(start 0.120396 0.2794)
			(end -0.12065 0.2794)
			(stroke
				(width 0.1)
				(type default)
			)
			(layer "F.Fab")
		)
		(fp_line
			(start -0.12065 0.3048)
			(end -0.67945 0.3048)
			(stroke
				(width 0.1)
				(type default)
			)
			(layer "F.Fab")
		)
		(fp_line
			(start -0.12065 0.2794)
			(end -0.12065 0.3048)
			(stroke
				(width 0.1)
				(type default)
			)
			(layer "F.Fab")
		)
		(fp_line
			(start -0.12065 -0.2794)
			(end 0.12065 -0.2794)
			(stroke
				(width 0.1)
				(type default)
			)
			(layer "F.Fab")
		)
		(fp_line
			(start -0.12065 -0.305054)
			(end -0.12065 -0.2794)
			(stroke
				(width 0.1)
				(type default)
			)
			(layer "F.Fab")
		)
		(fp_line
			(start -0.67945 0.3048)
			(end -0.67945 -0.305054)
			(stroke
				(width 0.1)
				(type default)
			)
			(layer "F.Fab")
		)
		(fp_line
			(start -0.67945 -0.305054)
			(end -0.12065 -0.305054)
			(stroke
				(width 0.1)
				(type default)
			)
			(layer "F.Fab")
		)
		(pad "1" smd circle
			(at -0.40005 0 180)
			(size 0 0)
			(layers "F.Cu" "F.Mask" "F.Paste")
			(net "SW_P12V_AUX_PVDDCR_CPU1_P1_FLT")
		)
		(pad "2" smd circle
			(at 0.40005 0 180)
			(size 0 0)
			(layers "F.Cu" "F.Mask" "F.Paste")
			(net "GND")
		)
	)
)
